(kicad_pcb
	(version 20260206)
	(generator "pcbnew")
	(generator_version "10.0")
	(general
		(thickness 1.6)
		(legacy_teardrops no)
	)
	(paper "A4")
	(title_block
		(title "01162023_DA0F0TEBIF0_F0T_Expander_BD_F_brd_V02_OCP.brd")
		(comment 1 "Grand Teton / footprints 8071-8077 of 9728")
	)
	(layers
		(0 "F.Cu" signal "TOP")
		(4 "In1.Cu" signal "GND")
		(6 "In2.Cu" signal "VCC")
		(8 "In3.Cu" signal "VCC1")
		(10 "In4.Cu" signal "GND1")
		(12 "In5.Cu" signal "IN1")
		(14 "In6.Cu" signal "GND2")
		(16 "In7.Cu" signal "IN2")
		(18 "In8.Cu" signal "GND3")
		(20 "In9.Cu" signal "IN3")
		(22 "In10.Cu" signal "GND4")
		(24 "In11.Cu" signal "IN4")
		(26 "In12.Cu" signal "GND5")
		(28 "In13.Cu" signal "IN5")
		(30 "In14.Cu" signal "GND6")
		(32 "In15.Cu" signal "IN6")
		(34 "In16.Cu" signal "GND7")
		(2 "B.Cu" signal "BOTTOM")
		(9 "F.Adhes" user "F.Adhesive")
		(11 "B.Adhes" user "B.Adhesive")
		(13 "F.Paste" user "Package Geometry/Pastemask Top")
		(15 "B.Paste" user "Package Geometry/Pastemask Bottom")
		(5 "F.SilkS" user "Ref Des/Silkscreen Top")
		(7 "B.SilkS" user "Ref Des/Silkscreen Bottom")
		(1 "F.Mask" user "Board Geometry/Soldermask Top")
		(3 "B.Mask" user "Board Geometry/Soldermask Bottom")
		(17 "Dwgs.User" user "User.Drawings")
		(19 "Cmts.User" user "User.Comments")
		(21 "Eco1.User" user "User.Eco1")
		(23 "Eco2.User" user "User.Eco2")
		(25 "Edge.Cuts" user "Board Geometry/Outline")
		(27 "Margin" user)
		(31 "F.CrtYd" user "Package Geometry/Place Bound Top")
		(29 "B.CrtYd" user "Package Geometry/Place Bound Bottom")
		(35 "F.Fab" user "Ref Des/Assembly Top")
		(33 "B.Fab" user "Ref Des/Assembly Bottom")
	)
	(footprint ""
		(layer "B.Cu")
		(at 285.83001 -295.221914)
		(property "Reference" "C1611"
			(at 0 0 0)
			(layer "B.SilkS")
			(hide yes)
			(effects
				(font
					(size 1.27 1.27)
				)
				(justify mirror)
			)
		)
		(property "Value" ""
			(at 0 0 0)
			(layer "B.Fab")
			(effects
				(font
					(size 1.27 1.27)
				)
				(justify mirror)
			)
		)
		(duplicate_pad_numbers_are_jumpers no)
		(fp_line
			(start -1.2954 -0.5842)
			(end -1.2954 0.5842)
			(stroke
				(width 0.1524)
				(type default)
			)
			(layer "B.SilkS")
		)
		(fp_line
			(start -1.2954 0.5842)
			(end 1.2954 0.5842)
			(stroke
				(width 0.1524)
				(type default)
			)
			(layer "B.SilkS")
		)
		(fp_line
			(start 1.2954 -0.5842)
			(end -1.2954 -0.5842)
			(stroke
				(width 0.1524)
				(type default)
			)
			(layer "B.SilkS")
		)
		(fp_line
			(start 1.2954 0.5842)
			(end 1.2954 -0.5842)
			(stroke
				(width 0.1524)
				(type default)
			)
			(layer "B.SilkS")
		)
		(fp_line
			(start -1.1938 -0.4064)
			(end -1.1938 0.4064)
			(stroke
				(width 0.1)
				(type default)
			)
			(layer "B.Fab")
		)
		(fp_line
			(start -1.1938 0.4064)
			(end -0.8636 0.4064)
			(stroke
				(width 0.1)
				(type default)
			)
			(layer "B.Fab")
		)
		(fp_line
			(start -0.8636 -0.4572)
			(end -0.8636 -0.4064)
			(stroke
				(width 0.1)
				(type default)
			)
			(layer "B.Fab")
		)
		(fp_line
			(start -0.8636 -0.4064)
			(end -1.1938 -0.4064)
			(stroke
				(width 0.1)
				(type default)
			)
			(layer "B.Fab")
		)
		(fp_line
			(start -0.8636 0.4064)
			(end -0.8636 0.4572)
			(stroke
				(width 0.1)
				(type default)
			)
			(layer "B.Fab")
		)
		(fp_line
			(start -0.8636 0.4572)
			(end 0.8636 0.4572)
			(stroke
				(width 0.1)
				(type default)
			)
			(layer "B.Fab")
		)
		(fp_line
			(start 0.8636 -0.4572)
			(end -0.8636 -0.4572)
			(stroke
				(width 0.1)
				(type default)
			)
			(layer "B.Fab")
		)
		(fp_line
			(start 0.8636 -0.4064)
			(end 0.8636 -0.4572)
			(stroke
				(width 0.1)
				(type default)
			)
			(layer "B.Fab")
		)
		(fp_line
			(start 0.8636 0.4064)
			(end 1.1938 0.4064)
			(stroke
				(width 0.1)
				(type default)
			)
			(layer "B.Fab")
		)
		(fp_line
			(start 0.8636 0.4572)
			(end 0.8636 0.4064)
			(stroke
				(width 0.1)
				(type default)
			)
			(layer "B.Fab")
		)
		(fp_line
			(start 1.1938 -0.4064)
			(end 0.8636 -0.4064)
			(stroke
				(width 0.1)
				(type default)
			)
			(layer "B.Fab")
		)
		(fp_line
			(start 1.1938 0.4064)
			(end 1.1938 -0.4064)
			(stroke
				(width 0.1)
				(type default)
			)
			(layer "B.Fab")
		)
		(pad "1" smd rect
			(at 0.7366 0 270)
			(size 0.7112 0.8128)
			(layers "B.Cu" "B.Mask" "B.Paste")
			(net "P0V8_PEX2")
		)
		(pad "2" smd rect
			(at -0.7366 0 270)
			(size 0.7112 0.8128)
			(layers "B.Cu" "B.Mask" "B.Paste")
			(net "GND")
		)
	)
	(footprint ""
		(layer "B.Cu")
		(at 219.939362 -285.911544)
		(property "Reference" "PC232"
			(at 0 0 0)
			(layer "B.SilkS")
			(hide yes)
			(effects
				(font
					(size 1.27 1.27)
				)
				(justify mirror)
			)
		)
		(property "Value" ""
			(at 0 0 0)
			(layer "B.Fab")
			(effects
				(font
					(size 1.27 1.27)
				)
				(justify mirror)
			)
		)
		(duplicate_pad_numbers_are_jumpers no)
		(fp_line
			(start -1.524 -0.762)
			(end -1.524 0.762)
			(stroke
				(width 0.1524)
				(type default)
			)
			(layer "B.SilkS")
		)
		(fp_line
			(start -1.524 0.762)
			(end 1.524 0.762)
			(stroke
				(width 0.1524)
				(type default)
			)
			(layer "B.SilkS")
		)
		(fp_line
			(start 1.524 -0.762)
			(end -1.524 -0.762)
			(stroke
				(width 0.1524)
				(type default)
			)
			(layer "B.SilkS")
		)
		(fp_line
			(start 1.524 0.762)
			(end 1.524 -0.762)
			(stroke
				(width 0.1524)
				(type default)
			)
			(layer "B.SilkS")
		)
		(fp_line
			(start -1.1049 -0.724916)
			(end 1.1049 -0.724916)
			(stroke
				(width 0.1)
				(type default)
			)
			(layer "B.Fab")
		)
		(fp_line
			(start -1.1049 0.724916)
			(end -1.1049 -0.724916)
			(stroke
				(width 0.1)
				(type default)
			)
			(layer "B.Fab")
		)
		(fp_line
			(start 1.1049 -0.724916)
			(end 1.1049 0.724916)
			(stroke
				(width 0.1)
				(type default)
			)
			(layer "B.Fab")
		)
		(fp_line
			(start 1.1049 0.724916)
			(end -1.1049 0.724916)
			(stroke
				(width 0.1)
				(type default)
			)
			(layer "B.Fab")
		)
		(pad "1" smd rect
			(at 0.889 0)
			(size 1.016 1.27)
			(layers "B.Cu" "B.Mask" "B.Paste")
			(net "P1V25_PEX1_R")
		)
		(pad "2" smd rect
			(at -0.889 0)
			(size 1.016 1.27)
			(layers "B.Cu" "B.Mask" "B.Paste")
			(net "GND")
		)
	)
	(footprint ""
		(layer "B.Cu")
		(at 354.659184 -321.15125 -90)
		(property "Reference" "R6544"
			(at 0 0 90)
			(layer "B.SilkS")
			(hide yes)
			(effects
				(font
					(size 1.27 1.27)
				)
				(justify mirror)
			)
		)
		(property "Value" ""
			(at 0 0 90)
			(layer "B.Fab")
			(effects
				(font
					(size 1.27 1.27)
				)
				(justify mirror)
			)
		)
		(duplicate_pad_numbers_are_jumpers no)
		(fp_line
			(start -0.7874 0.4064)
			(end 0.7874 0.4064)
			(stroke
				(width 0.1524)
				(type default)
			)
			(layer "B.SilkS")
		)
		(fp_line
			(start 0.7874 0.4064)
			(end 0.7874 -0.4064)
			(stroke
				(width 0.1524)
				(type default)
			)
			(layer "B.SilkS")
		)
		(fp_line
			(start -0.7874 -0.4064)
			(end -0.7874 0.4064)
			(stroke
				(width 0.1524)
				(type default)
			)
			(layer "B.SilkS")
		)
		(fp_line
			(start 0.7874 -0.4064)
			(end -0.7874 -0.4064)
			(stroke
				(width 0.1524)
				(type default)
			)
			(layer "B.SilkS")
		)
		(fp_line
			(start -0.67945 0.3048)
			(end -0.120396 0.3048)
			(stroke
				(width 0.1)
				(type default)
			)
			(layer "B.Fab")
		)
		(fp_line
			(start -0.120396 0.3048)
			(end -0.120396 0.2794)
			(stroke
				(width 0.1)
				(type default)
			)
			(layer "B.Fab")
		)
		(fp_line
			(start 0.12065 0.3048)
			(end 0.67945 0.3048)
			(stroke
				(width 0.1)
				(type default)
			)
			(layer "B.Fab")
		)
		(fp_line
			(start 0.67945 0.3048)
			(end 0.67945 -0.305054)
			(stroke
				(width 0.1)
				(type default)
			)
			(layer "B.Fab")
		)
		(fp_line
			(start -0.120396 0.2794)
			(end 0.12065 0.2794)
			(stroke
				(width 0.1)
				(type default)
			)
			(layer "B.Fab")
		)
		(fp_line
			(start 0.12065 0.2794)
			(end 0.12065 0.3048)
			(stroke
				(width 0.1)
				(type default)
			)
			(layer "B.Fab")
		)
		(fp_line
			(start -0.12065 -0.2794)
			(end -0.12065 -0.3048)
			(stroke
				(width 0.1)
				(type default)
			)
			(layer "B.Fab")
		)
		(fp_line
			(start 0.12065 -0.2794)
			(end -0.12065 -0.2794)
			(stroke
				(width 0.1)
				(type default)
			)
			(layer "B.Fab")
		)
		(fp_line
			(start -0.67945 -0.3048)
			(end -0.67945 0.3048)
			(stroke
				(width 0.1)
				(type default)
			)
			(layer "B.Fab")
		)
		(fp_line
			(start -0.12065 -0.3048)
			(end -0.67945 -0.3048)
			(stroke
				(width 0.1)
				(type default)
			)
			(layer "B.Fab")
		)
		(fp_line
			(start 0.12065 -0.305054)
			(end 0.12065 -0.2794)
			(stroke
				(width 0.1)
				(type default)
			)
			(layer "B.Fab")
		)
		(fp_line
			(start 0.67945 -0.305054)
			(end 0.12065 -0.305054)
			(stroke
				(width 0.1)
				(type default)
			)
			(layer "B.Fab")
		)
		(pad "1" smd circle
			(at 0.40005 0 90)
			(size 0 0)
			(layers "B.Cu" "B.Mask" "B.Paste")
			(net "P0V8_SERDES_VDDA_PEX3")
		)
		(pad "2" smd circle
			(at -0.40005 0 90)
			(size 0 0)
			(layers "B.Cu" "B.Mask" "B.Paste")
			(net "P0V8_SERDES_VDDA_PEX3_C7")
		)
	)
	(footprint ""
		(layer "B.Cu")
		(at 287.099756 -299.699934 -90)
		(property "Reference" "C1723"
			(at 0 0 90)
			(layer "B.SilkS")
			(hide yes)
			(effects
				(font
					(size 1.27 1.27)
				)
				(justify mirror)
			)
		)
		(property "Value" ""
			(at 0 0 90)
			(layer "B.Fab")
			(effects
				(font
					(size 1.27 1.27)
				)
				(justify mirror)
			)
		)
		(duplicate_pad_numbers_are_jumpers no)
		(fp_line
			(start -0.299974 0.150114)
			(end 0.299974 0.150114)
			(stroke
				(width 0.1)
				(type default)
			)
			(layer "B.Fab")
		)
		(fp_line
			(start 0.299974 0.150114)
			(end 0.299974 -0.150114)
			(stroke
				(width 0.1)
				(type default)
			)
			(layer "B.Fab")
		)
		(fp_line
			(start -0.299974 -0.150114)
			(end -0.299974 0.150114)
			(stroke
				(width 0.1)
				(type default)
			)
			(layer "B.Fab")
		)
		(fp_line
			(start 0.299974 -0.150114)
			(end -0.299974 -0.150114)
			(stroke
				(width 0.1)
				(type default)
			)
			(layer "B.Fab")
		)
		(pad "1" smd rect
			(at 0.2667 0 90)
			(size 0.3048 0.381)
			(layers "B.Cu" "B.Mask" "B.Paste")
			(net "P0V8_SERDES_VDDA_PEX2")
		)
		(pad "2" smd rect
			(at -0.2667 0 90)
			(size 0.3048 0.381)
			(layers "B.Cu" "B.Mask" "B.Paste")
			(net "GND")
		)
	)
	(footprint ""
		(layer "B.Cu")
		(at 102.629208 -394.194538 90)
		(property "Reference" "C3632"
			(at 0 0 90)
			(layer "B.SilkS")
			(hide yes)
			(effects
				(font
					(size 1.27 1.27)
				)
				(justify mirror)
			)
		)
		(property "Value" ""
			(at 0 0 90)
			(layer "B.Fab")
			(effects
				(font
					(size 1.27 1.27)
				)
				(justify mirror)
			)
		)
		(duplicate_pad_numbers_are_jumpers no)
		(fp_line
			(start 0.7874 -0.4064)
			(end -0.7874 -0.4064)
			(stroke
				(width 0.1524)
				(type default)
			)
			(layer "B.SilkS")
		)
		(fp_line
			(start -0.7874 -0.4064)
			(end -0.7874 0.4064)
			(stroke
				(width 0.1524)
				(type default)
			)
			(layer "B.SilkS")
		)
		(fp_line
			(start 0.7874 0.4064)
			(end 0.7874 -0.4064)
			(stroke
				(width 0.1524)
				(type default)
			)
			(layer "B.SilkS")
		)
		(fp_line
			(start -0.7874 0.4064)
			(end 0.7874 0.4064)
			(stroke
				(width 0.1524)
				(type default)
			)
			(layer "B.SilkS")
		)
		(fp_line
			(start 0.67945 -0.305054)
			(end 0.12065 -0.305054)
			(stroke
				(width 0.1)
				(type default)
			)
			(layer "B.Fab")
		)
		(fp_line
			(start 0.12065 -0.305054)
			(end 0.12065 -0.2794)
			(stroke
				(width 0.1)
				(type default)
			)
			(layer "B.Fab")
		)
		(fp_line
			(start -0.12065 -0.3048)
			(end -0.67945 -0.3048)
			(stroke
				(width 0.1)
				(type default)
			)
			(layer "B.Fab")
		)
		(fp_line
			(start -0.67945 -0.3048)
			(end -0.67945 0.3048)
			(stroke
				(width 0.1)
				(type default)
			)
			(layer "B.Fab")
		)
		(fp_line
			(start 0.12065 -0.2794)
			(end -0.12065 -0.2794)
			(stroke
				(width 0.1)
				(type default)
			)
			(layer "B.Fab")
		)
		(fp_line
			(start -0.12065 -0.2794)
			(end -0.12065 -0.3048)
			(stroke
				(width 0.1)
				(type default)
			)
			(layer "B.Fab")
		)
		(fp_line
			(start 0.12065 0.2794)
			(end 0.12065 0.3048)
			(stroke
				(width 0.1)
				(type default)
			)
			(layer "B.Fab")
		)
		(fp_line
			(start -0.120396 0.2794)
			(end 0.12065 0.2794)
			(stroke
				(width 0.1)
				(type default)
			)
			(layer "B.Fab")
		)
		(fp_line
			(start 0.67945 0.3048)
			(end 0.67945 -0.305054)
			(stroke
				(width 0.1)
				(type default)
			)
			(layer "B.Fab")
		)
		(fp_line
			(start 0.12065 0.3048)
			(end 0.67945 0.3048)
			(stroke
				(width 0.1)
				(type default)
			)
			(layer "B.Fab")
		)
		(fp_line
			(start -0.120396 0.3048)
			(end -0.120396 0.2794)
			(stroke
				(width 0.1)
				(type default)
			)
			(layer "B.Fab")
		)
		(fp_line
			(start -0.67945 0.3048)
			(end -0.120396 0.3048)
			(stroke
				(width 0.1)
				(type default)
			)
			(layer "B.Fab")
		)
		(pad "1" smd circle
			(at 0.40005 0 270)
			(size 0 0)
			(layers "B.Cu" "B.Mask" "B.Paste")
			(net "P3V3_BIC_USB_HUB")
		)
		(pad "2" smd circle
			(at -0.40005 0 270)
			(size 0 0)
			(layers "B.Cu" "B.Mask" "B.Paste")
			(net "GND")
		)
	)
	(footprint ""
		(layer "B.Cu")
		(at 378.079 -244.729 180)
		(property "Reference" "R936"
			(at 0 0 0)
			(layer "B.SilkS")
			(hide yes)
			(effects
				(font
					(size 1.27 1.27)
				)
				(justify mirror)
			)
		)
		(property "Value" ""
			(at 0 0 0)
			(layer "B.Fab")
			(effects
				(font
					(size 1.27 1.27)
				)
				(justify mirror)
			)
		)
		(duplicate_pad_numbers_are_jumpers no)
		(fp_line
			(start 0.7874 0.4064)
			(end 0.7874 -0.4064)
			(stroke
				(width 0.1524)
				(type default)
			)
			(layer "B.SilkS")
		)
		(fp_line
			(start 0.7874 -0.4064)
			(end -0.7874 -0.4064)
			(stroke
				(width 0.1524)
				(type default)
			)
			(layer "B.SilkS")
		)
		(fp_line
			(start -0.7874 0.4064)
			(end 0.7874 0.4064)
			(stroke
				(width 0.1524)
				(type default)
			)
			(layer "B.SilkS")
		)
		(fp_line
			(start -0.7874 -0.4064)
			(end -0.7874 0.4064)
			(stroke
				(width 0.1524)
				(type default)
			)
			(layer "B.SilkS")
		)
		(fp_line
			(start 0.67945 0.3048)
			(end 0.67945 -0.305054)
			(stroke
				(width 0.1)
				(type default)
			)
			(layer "B.Fab")
		)
		(fp_line
			(start 0.67945 -0.305054)
			(end 0.12065 -0.305054)
			(stroke
				(width 0.1)
				(type default)
			)
			(layer "B.Fab")
		)
		(fp_line
			(start 0.12065 0.3048)
			(end 0.67945 0.3048)
			(stroke
				(width 0.1)
				(type default)
			)
			(layer "B.Fab")
		)
		(fp_line
			(start 0.12065 0.2794)
			(end 0.12065 0.3048)
			(stroke
				(width 0.1)
				(type default)
			)
			(layer "B.Fab")
		)
		(fp_line
			(start 0.12065 -0.2794)
			(end -0.12065 -0.2794)
			(stroke
				(width 0.1)
				(type default)
			)
			(layer "B.Fab")
		)
		(fp_line
			(start 0.12065 -0.305054)
			(end 0.12065 -0.2794)
			(stroke
				(width 0.1)
				(type default)
			)
			(layer "B.Fab")
		)
		(fp_line
			(start -0.120396 0.3048)
			(end -0.120396 0.2794)
			(stroke
				(width 0.1)
				(type default)
			)
			(layer "B.Fab")
		)
		(fp_line
			(start -0.120396 0.2794)
			(end 0.12065 0.2794)
			(stroke
				(width 0.1)
				(type default)
			)
			(layer "B.Fab")
		)
		(fp_line
			(start -0.12065 -0.2794)
			(end -0.12065 -0.3048)
			(stroke
				(width 0.1)
				(type default)
			)
			(layer "B.Fab")
		)
		(fp_line
			(start -0.12065 -0.3048)
			(end -0.67945 -0.3048)
			(stroke
				(width 0.1)
				(type default)
			)
			(layer "B.Fab")
		)
		(fp_line
			(start -0.67945 0.3048)
			(end -0.120396 0.3048)
			(stroke
				(width 0.1)
				(type default)
			)
			(layer "B.Fab")
		)
		(fp_line
			(start -0.67945 -0.3048)
			(end -0.67945 0.3048)
			(stroke
				(width 0.1)
				(type default)
			)
			(layer "B.Fab")
		)
		(pad "1" smd circle
			(at 0.40005 0)
			(size 0 0)
			(layers "B.Cu" "B.Mask" "B.Paste")
			(net "UART_PEX1_SDB_BUF_R_TX")
		)
		(pad "2" smd circle
			(at -0.40005 0)
			(size 0 0)
			(layers "B.Cu" "B.Mask" "B.Paste")
			(net "UART_PEX1_SDB_BUF_TX")
		)
	)
	(footprint ""
		(layer "B.Cu")
		(at 189.371478 -115.608608)
		(property "Reference" "C899"
			(at 0 0 0)
			(layer "B.SilkS")
			(hide yes)
			(effects
				(font
					(size 1.27 1.27)
				)
				(justify mirror)
			)
		)
		(property "Value" ""
			(at 0 0 0)
			(layer "B.Fab")
			(effects
				(font
					(size 1.27 1.27)
				)
				(justify mirror)
			)
		)
		(duplicate_pad_numbers_are_jumpers no)
		(fp_line
			(start -0.7874 -0.4064)
			(end -0.7874 0.4064)
			(stroke
				(width 0.1524)
				(type default)
			)
			(layer "B.SilkS")
		)
		(fp_line
			(start -0.7874 0.4064)
			(end 0.7874 0.4064)
			(stroke
				(width 0.1524)
				(type default)
			)
			(layer "B.SilkS")
		)
		(fp_line
			(start 0.7874 -0.4064)
			(end -0.7874 -0.4064)
			(stroke
				(width 0.1524)
				(type default)
			)
			(layer "B.SilkS")
		)
		(fp_line
			(start 0.7874 0.4064)
			(end 0.7874 -0.4064)
			(stroke
				(width 0.1524)
				(type default)
			)
			(layer "B.SilkS")
		)
		(fp_line
			(start -0.67945 -0.3048)
			(end -0.67945 0.3048)
			(stroke
				(width 0.1)
				(type default)
			)
			(layer "B.Fab")
		)
		(fp_line
			(start -0.67945 0.3048)
			(end -0.120396 0.3048)
			(stroke
				(width 0.1)
				(type default)
			)
			(layer "B.Fab")
		)
		(fp_line
			(start -0.12065 -0.3048)
			(end -0.67945 -0.3048)
			(stroke
				(width 0.1)
				(type default)
			)
			(layer "B.Fab")
		)
		(fp_line
			(start -0.12065 -0.2794)
			(end -0.12065 -0.3048)
			(stroke
				(width 0.1)
				(type default)
			)
			(layer "B.Fab")
		)
		(fp_line
			(start -0.120396 0.2794)
			(end 0.12065 0.2794)
			(stroke
				(width 0.1)
				(type default)
			)
			(layer "B.Fab")
		)
		(fp_line
			(start -0.120396 0.3048)
			(end -0.120396 0.2794)
			(stroke
				(width 0.1)
				(type default)
			)
			(layer "B.Fab")
		)
		(fp_line
			(start 0.12065 -0.305054)
			(end 0.12065 -0.2794)
			(stroke
				(width 0.1)
				(type default)
			)
			(layer "B.Fab")
		)
		(fp_line
			(start 0.12065 -0.2794)
			(end -0.12065 -0.2794)
			(stroke
				(width 0.1)
				(type default)
			)
			(layer "B.Fab")
		)
		(fp_line
			(start 0.12065 0.2794)
			(end 0.12065 0.3048)
			(stroke
				(width 0.1)
				(type default)
			)
			(layer "B.Fab")
		)
		(fp_line
			(start 0.12065 0.3048)
			(end 0.67945 0.3048)
			(stroke
				(width 0.1)
				(type default)
			)
			(layer "B.Fab")
		)
		(fp_line
			(start 0.67945 -0.305054)
			(end 0.12065 -0.305054)
			(stroke
				(width 0.1)
				(type default)
			)
			(layer "B.Fab")
		)
		(fp_line
			(start 0.67945 0.3048)
			(end 0.67945 -0.305054)
			(stroke
				(width 0.1)
				(type default)
			)
			(layer "B.Fab")
		)
		(pad "1" smd circle
			(at 0.40005 0 180)
			(size 0 0)
			(layers "B.Cu" "B.Mask" "B.Paste")
			(net "P3V3_NIC3")
		)
		(pad "2" smd circle
			(at -0.40005 0 180)
			(size 0 0)
			(layers "B.Cu" "B.Mask" "B.Paste")
			(net "GND")
		)
	)
)
